(kicad_pcb
	(version 20260206)
	(generator "pcbnew")
	(generator_version "10.0")
	(general
		(thickness 1.6)
		(legacy_teardrops no)
	)
	(paper "A4")
	(title_block
		(title "01162023_DA0F0TEBIF0_F0T_Expander_BD_F_brd_V02_OCP.brd")
		(comment 1 "Grand Teton / footprints 4092-4097 of 9728")
	)
	(layers
		(0 "F.Cu" signal "TOP")
		(4 "In1.Cu" signal "GND")
		(6 "In2.Cu" signal "VCC")
		(8 "In3.Cu" signal "VCC1")
		(10 "In4.Cu" signal "GND1")
		(12 "In5.Cu" signal "IN1")
		(14 "In6.Cu" signal "GND2")
		(16 "In7.Cu" signal "IN2")
		(18 "In8.Cu" signal "GND3")
		(20 "In9.Cu" signal "IN3")
		(22 "In10.Cu" signal "GND4")
		(24 "In11.Cu" signal "IN4")
		(26 "In12.Cu" signal "GND5")
		(28 "In13.Cu" signal "IN5")
		(30 "In14.Cu" signal "GND6")
		(32 "In15.Cu" signal "IN6")
		(34 "In16.Cu" signal "GND7")
		(2 "B.Cu" signal "BOTTOM")
		(9 "F.Adhes" user "F.Adhesive")
		(11 "B.Adhes" user "B.Adhesive")
		(13 "F.Paste" user "Package Geometry/Pastemask Top")
		(15 "B.Paste" user "Package Geometry/Pastemask Bottom")
		(5 "F.SilkS" user "Ref Des/Silkscreen Top")
		(7 "B.SilkS" user "Ref Des/Silkscreen Bottom")
		(1 "F.Mask" user "Board Geometry/Soldermask Top")
		(3 "B.Mask" user "Board Geometry/Soldermask Bottom")
		(17 "Dwgs.User" user "User.Drawings")
		(19 "Cmts.User" user "User.Comments")
		(21 "Eco1.User" user "User.Eco1")
		(23 "Eco2.User" user "User.Eco2")
		(25 "Edge.Cuts" user "Board Geometry/Outline")
		(27 "Margin" user)
		(31 "F.CrtYd" user "Package Geometry/Place Bound Top")
		(29 "B.CrtYd" user "Package Geometry/Place Bound Bottom")
		(35 "F.Fab" user "Ref Des/Assembly Top")
		(33 "B.Fab" user "Ref Des/Assembly Bottom")
	)
	(footprint ""
		(layer "F.Cu")
		(at 345.76131 -259.782564 180)
		(property "Reference" "PR141"
			(at 0 0 180)
			(layer "F.SilkS")
			(hide yes)
			(effects
				(font
					(size 1.27 1.27)
				)
			)
		)
		(property "Value" ""
			(at 0 0 180)
			(layer "F.Fab")
			(effects
				(font
					(size 1.27 1.27)
				)
			)
		)
		(duplicate_pad_numbers_are_jumpers no)
		(fp_line
			(start 0.7874 0.4064)
			(end -0.7874 0.4064)
			(stroke
				(width 0.1524)
				(type default)
			)
			(layer "F.SilkS")
		)
		(fp_line
			(start 0.7874 -0.4064)
			(end 0.7874 0.4064)
			(stroke
				(width 0.1524)
				(type default)
			)
			(layer "F.SilkS")
		)
		(fp_line
			(start -0.7874 0.4064)
			(end -0.7874 -0.4064)
			(stroke
				(width 0.1524)
				(type default)
			)
			(layer "F.SilkS")
		)
		(fp_line
			(start -0.7874 -0.4064)
			(end 0.7874 -0.4064)
			(stroke
				(width 0.1524)
				(type default)
			)
			(layer "F.SilkS")
		)
		(fp_line
			(start 0.67945 0.3048)
			(end 0.120396 0.3048)
			(stroke
				(width 0.1)
				(type default)
			)
			(layer "F.Fab")
		)
		(fp_line
			(start 0.67945 -0.3048)
			(end 0.67945 0.3048)
			(stroke
				(width 0.1)
				(type default)
			)
			(layer "F.Fab")
		)
		(fp_line
			(start 0.12065 -0.2794)
			(end 0.12065 -0.3048)
			(stroke
				(width 0.1)
				(type default)
			)
			(layer "F.Fab")
		)
		(fp_line
			(start 0.12065 -0.3048)
			(end 0.67945 -0.3048)
			(stroke
				(width 0.1)
				(type default)
			)
			(layer "F.Fab")
		)
		(fp_line
			(start 0.120396 0.3048)
			(end 0.120396 0.2794)
			(stroke
				(width 0.1)
				(type default)
			)
			(layer "F.Fab")
		)
		(fp_line
			(start 0.120396 0.2794)
			(end -0.12065 0.2794)
			(stroke
				(width 0.1)
				(type default)
			)
			(layer "F.Fab")
		)
		(fp_line
			(start -0.12065 0.3048)
			(end -0.67945 0.3048)
			(stroke
				(width 0.1)
				(type default)
			)
			(layer "F.Fab")
		)
		(fp_line
			(start -0.12065 0.2794)
			(end -0.12065 0.3048)
			(stroke
				(width 0.1)
				(type default)
			)
			(layer "F.Fab")
		)
		(fp_line
			(start -0.12065 -0.2794)
			(end 0.12065 -0.2794)
			(stroke
				(width 0.1)
				(type default)
			)
			(layer "F.Fab")
		)
		(fp_line
			(start -0.12065 -0.305054)
			(end -0.12065 -0.2794)
			(stroke
				(width 0.1)
				(type default)
			)
			(layer "F.Fab")
		)
		(fp_line
			(start -0.67945 0.3048)
			(end -0.67945 -0.305054)
			(stroke
				(width 0.1)
				(type default)
			)
			(layer "F.Fab")
		)
		(fp_line
			(start -0.67945 -0.305054)
			(end -0.12065 -0.305054)
			(stroke
				(width 0.1)
				(type default)
			)
			(layer "F.Fab")
		)
		(pad "1" smd circle
			(at -0.40005 0 180)
			(size 0 0)
			(layers "F.Cu" "F.Mask" "F.Paste")
			(net "P0V8_PEX2_ADDR")
		)
		(pad "2" smd circle
			(at 0.40005 0 180)
			(size 0 0)
			(layers "F.Cu" "F.Mask" "F.Paste")
			(net "GND")
		)
	)
	(footprint ""
		(layer "F.Cu")
		(at 381.587756 -294.819832)
		(property "Reference" "C3549"
			(at 0 0 0)
			(layer "F.SilkS")
			(hide yes)
			(effects
				(font
					(size 1.27 1.27)
				)
			)
		)
		(property "Value" ""
			(at 0 0 0)
			(layer "F.Fab")
			(effects
				(font
					(size 1.27 1.27)
				)
			)
		)
		(duplicate_pad_numbers_are_jumpers no)
		(fp_line
			(start -1.2954 -0.5842)
			(end 1.2954 -0.5842)
			(stroke
				(width 0.1524)
				(type default)
			)
			(layer "F.SilkS")
		)
		(fp_line
			(start -1.2954 0.5842)
			(end -1.2954 -0.5842)
			(stroke
				(width 0.1524)
				(type default)
			)
			(layer "F.SilkS")
		)
		(fp_line
			(start 1.2954 -0.5842)
			(end 1.2954 0.5842)
			(stroke
				(width 0.1524)
				(type default)
			)
			(layer "F.SilkS")
		)
		(fp_line
			(start 1.2954 0.5842)
			(end -1.2954 0.5842)
			(stroke
				(width 0.1524)
				(type default)
			)
			(layer "F.SilkS")
		)
		(fp_line
			(start -1.1938 -0.4064)
			(end -0.8636 -0.4064)
			(stroke
				(width 0.1)
				(type default)
			)
			(layer "F.Fab")
		)
		(fp_line
			(start -1.1938 0.4064)
			(end -1.1938 -0.4064)
			(stroke
				(width 0.1)
				(type default)
			)
			(layer "F.Fab")
		)
		(fp_line
			(start -0.8636 -0.4572)
			(end 0.8636 -0.4572)
			(stroke
				(width 0.1)
				(type default)
			)
			(layer "F.Fab")
		)
		(fp_line
			(start -0.8636 -0.4064)
			(end -0.8636 -0.4572)
			(stroke
				(width 0.1)
				(type default)
			)
			(layer "F.Fab")
		)
		(fp_line
			(start -0.8636 0.4064)
			(end -1.1938 0.4064)
			(stroke
				(width 0.1)
				(type default)
			)
			(layer "F.Fab")
		)
		(fp_line
			(start -0.8636 0.4572)
			(end -0.8636 0.4064)
			(stroke
				(width 0.1)
				(type default)
			)
			(layer "F.Fab")
		)
		(fp_line
			(start 0.8636 -0.4572)
			(end 0.8636 -0.4064)
			(stroke
				(width 0.1)
				(type default)
			)
			(layer "F.Fab")
		)
		(fp_line
			(start 0.8636 -0.4064)
			(end 1.1938 -0.4064)
			(stroke
				(width 0.1)
				(type default)
			)
			(layer "F.Fab")
		)
		(fp_line
			(start 0.8636 0.4064)
			(end 0.8636 0.4572)
			(stroke
				(width 0.1)
				(type default)
			)
			(layer "F.Fab")
		)
		(fp_line
			(start 0.8636 0.4572)
			(end -0.8636 0.4572)
			(stroke
				(width 0.1)
				(type default)
			)
			(layer "F.Fab")
		)
		(fp_line
			(start 1.1938 -0.4064)
			(end 1.1938 0.4064)
			(stroke
				(width 0.1)
				(type default)
			)
			(layer "F.Fab")
		)
		(fp_line
			(start 1.1938 0.4064)
			(end 0.8636 0.4064)
			(stroke
				(width 0.1)
				(type default)
			)
			(layer "F.Fab")
		)
		(pad "1" smd rect
			(at -0.7366 0 270)
			(size 0.7112 0.8128)
			(layers "F.Cu" "F.Mask" "F.Paste")
			(net "PCEPLL2_VDDA18_PEX3")
		)
		(pad "2" smd rect
			(at 0.7366 0 270)
			(size 0.7112 0.8128)
			(layers "F.Cu" "F.Mask" "F.Paste")
			(net "GND")
		)
	)
	(footprint ""
		(layer "F.Cu")
		(at 250.96343 -92.096336 -90)
		(property "Reference" "R1070"
			(at 0 0 270)
			(layer "F.SilkS")
			(hide yes)
			(effects
				(font
					(size 1.27 1.27)
				)
			)
		)
		(property "Value" ""
			(at 0 0 270)
			(layer "F.Fab")
			(effects
				(font
					(size 1.27 1.27)
				)
			)
		)
		(duplicate_pad_numbers_are_jumpers no)
		(fp_line
			(start -0.7874 0.4064)
			(end -0.7874 -0.4064)
			(stroke
				(width 0.1524)
				(type default)
			)
			(layer "F.SilkS")
		)
		(fp_line
			(start 0.7874 0.4064)
			(end -0.7874 0.4064)
			(stroke
				(width 0.1524)
				(type default)
			)
			(layer "F.SilkS")
		)
		(fp_line
			(start -0.7874 -0.4064)
			(end 0.7874 -0.4064)
			(stroke
				(width 0.1524)
				(type default)
			)
			(layer "F.SilkS")
		)
		(fp_line
			(start 0.7874 -0.4064)
			(end 0.7874 0.4064)
			(stroke
				(width 0.1524)
				(type default)
			)
			(layer "F.SilkS")
		)
		(fp_line
			(start -0.67945 0.3048)
			(end -0.67945 -0.305054)
			(stroke
				(width 0.1)
				(type default)
			)
			(layer "F.Fab")
		)
		(fp_line
			(start -0.12065 0.3048)
			(end -0.67945 0.3048)
			(stroke
				(width 0.1)
				(type default)
			)
			(layer "F.Fab")
		)
		(fp_line
			(start 0.120396 0.3048)
			(end 0.120396 0.2794)
			(stroke
				(width 0.1)
				(type default)
			)
			(layer "F.Fab")
		)
		(fp_line
			(start 0.67945 0.3048)
			(end 0.120396 0.3048)
			(stroke
				(width 0.1)
				(type default)
			)
			(layer "F.Fab")
		)
		(fp_line
			(start -0.12065 0.2794)
			(end -0.12065 0.3048)
			(stroke
				(width 0.1)
				(type default)
			)
			(layer "F.Fab")
		)
		(fp_line
			(start 0.120396 0.2794)
			(end -0.12065 0.2794)
			(stroke
				(width 0.1)
				(type default)
			)
			(layer "F.Fab")
		)
		(fp_line
			(start -0.12065 -0.2794)
			(end 0.12065 -0.2794)
			(stroke
				(width 0.1)
				(type default)
			)
			(layer "F.Fab")
		)
		(fp_line
			(start 0.12065 -0.2794)
			(end 0.12065 -0.3048)
			(stroke
				(width 0.1)
				(type default)
			)
			(layer "F.Fab")
		)
		(fp_line
			(start 0.12065 -0.3048)
			(end 0.67945 -0.3048)
			(stroke
				(width 0.1)
				(type default)
			)
			(layer "F.Fab")
		)
		(fp_line
			(start 0.67945 -0.3048)
			(end 0.67945 0.3048)
			(stroke
				(width 0.1)
				(type default)
			)
			(layer "F.Fab")
		)
		(fp_line
			(start -0.67945 -0.305054)
			(end -0.12065 -0.305054)
			(stroke
				(width 0.1)
				(type default)
			)
			(layer "F.Fab")
		)
		(fp_line
			(start -0.12065 -0.305054)
			(end -0.12065 -0.2794)
			(stroke
				(width 0.1)
				(type default)
			)
			(layer "F.Fab")
		)
		(pad "1" smd circle
			(at -0.40005 0 270)
			(size 0 0)
			(layers "F.Cu" "F.Mask" "F.Paste")
			(net "GND")
		)
		(pad "2" smd circle
			(at 0.40005 0 270)
			(size 0 0)
			(layers "F.Cu" "F.Mask" "F.Paste")
			(net "FM_CK440Q_DEV_25M_EN")
		)
	)
	(footprint ""
		(layer "F.Cu")
		(at 52.243736 -42.84091)
		(property "Reference" "R517"
			(at 0 0 0)
			(layer "F.SilkS")
			(hide yes)
			(effects
				(font
					(size 1.27 1.27)
				)
			)
		)
		(property "Value" ""
			(at 0 0 0)
			(layer "F.Fab")
			(effects
				(font
					(size 1.27 1.27)
				)
			)
		)
		(duplicate_pad_numbers_are_jumpers no)
		(fp_line
			(start -0.7874 -0.4064)
			(end 0.7874 -0.4064)
			(stroke
				(width 0.1524)
				(type default)
			)
			(layer "F.SilkS")
		)
		(fp_line
			(start -0.7874 0.4064)
			(end -0.7874 -0.4064)
			(stroke
				(width 0.1524)
				(type default)
			)
			(layer "F.SilkS")
		)
		(fp_line
			(start 0.7874 -0.4064)
			(end 0.7874 0.4064)
			(stroke
				(width 0.1524)
				(type default)
			)
			(layer "F.SilkS")
		)
		(fp_line
			(start 0.7874 0.4064)
			(end -0.7874 0.4064)
			(stroke
				(width 0.1524)
				(type default)
			)
			(layer "F.SilkS")
		)
		(fp_line
			(start -0.67945 -0.305054)
			(end -0.12065 -0.305054)
			(stroke
				(width 0.1)
				(type default)
			)
			(layer "F.Fab")
		)
		(fp_line
			(start -0.67945 0.3048)
			(end -0.67945 -0.305054)
			(stroke
				(width 0.1)
				(type default)
			)
			(layer "F.Fab")
		)
		(fp_line
			(start -0.12065 -0.305054)
			(end -0.12065 -0.2794)
			(stroke
				(width 0.1)
				(type default)
			)
			(layer "F.Fab")
		)
		(fp_line
			(start -0.12065 -0.2794)
			(end 0.12065 -0.2794)
			(stroke
				(width 0.1)
				(type default)
			)
			(layer "F.Fab")
		)
		(fp_line
			(start -0.12065 0.2794)
			(end -0.12065 0.3048)
			(stroke
				(width 0.1)
				(type default)
			)
			(layer "F.Fab")
		)
		(fp_line
			(start -0.12065 0.3048)
			(end -0.67945 0.3048)
			(stroke
				(width 0.1)
				(type default)
			)
			(layer "F.Fab")
		)
		(fp_line
			(start 0.120396 0.2794)
			(end -0.12065 0.2794)
			(stroke
				(width 0.1)
				(type default)
			)
			(layer "F.Fab")
		)
		(fp_line
			(start 0.120396 0.3048)
			(end 0.120396 0.2794)
			(stroke
				(width 0.1)
				(type default)
			)
			(layer "F.Fab")
		)
		(fp_line
			(start 0.12065 -0.3048)
			(end 0.67945 -0.3048)
			(stroke
				(width 0.1)
				(type default)
			)
			(layer "F.Fab")
		)
		(fp_line
			(start 0.12065 -0.2794)
			(end 0.12065 -0.3048)
			(stroke
				(width 0.1)
				(type default)
			)
			(layer "F.Fab")
		)
		(fp_line
			(start 0.67945 -0.3048)
			(end 0.67945 0.3048)
			(stroke
				(width 0.1)
				(type default)
			)
			(layer "F.Fab")
		)
		(fp_line
			(start 0.67945 0.3048)
			(end 0.120396 0.3048)
			(stroke
				(width 0.1)
				(type default)
			)
			(layer "F.Fab")
		)
		(pad "1" smd circle
			(at -0.40005 0)
			(size 0 0)
			(layers "F.Cu" "F.Mask" "F.Paste")
			(net "SSD1_ADC_A1")
		)
		(pad "2" smd circle
			(at 0.40005 0)
			(size 0 0)
			(layers "F.Cu" "F.Mask" "F.Paste")
			(net "P3V3_AUX")
		)
	)
	(footprint ""
		(layer "F.Cu")
		(at 373.911622 -71.458074 -90)
		(property "Reference" "PD116"
			(at 4.198874 -2.720848 90)
			(unlocked yes)
			(layer "F.SilkS")
			(effects
				(font
					(size 0.7874 0.5842)
					(thickness 0.1524)
				)
				(justify left)
			)
		)
		(property "Value" ""
			(at 0 0 270)
			(layer "F.Fab")
			(effects
				(font
					(size 1.27 1.27)
				)
			)
		)
		(duplicate_pad_numbers_are_jumpers no)
		(fp_line
			(start -3.656584 1.970024)
			(end 4.240784 1.970024)
			(stroke
				(width 0.1524)
				(type default)
			)
			(layer "F.SilkS")
		)
		(fp_line
			(start 4.240784 1.970024)
			(end 4.240784 -1.970024)
			(stroke
				(width 0.1524)
				(type default)
			)
			(layer "F.SilkS")
		)
		(fp_line
			(start -3.656584 -1.970024)
			(end -3.656584 1.970024)
			(stroke
				(width 0.1524)
				(type default)
			)
			(layer "F.SilkS")
		)
		(fp_line
			(start 4.240784 -1.970024)
			(end -3.656584 -1.970024)
			(stroke
				(width 0.1524)
				(type default)
			)
			(layer "F.SilkS")
		)
		(fp_poly
			(pts
				(xy 3.580384 1.970024) (xy 3.580384 -1.970024) (xy 4.240784 -1.970024) (xy 4.240784 1.970024)
			)
			(stroke
				(width 0)
				(type default)
			)
			(fill yes)
			(layer "F.SilkS")
		)
		(fp_line
			(start -2.3749 1.970024)
			(end 2.3749 1.970024)
			(stroke
				(width 0.1)
				(type default)
			)
			(layer "F.Fab")
		)
		(fp_line
			(start 2.3749 1.970024)
			(end 2.3749 -1.970024)
			(stroke
				(width 0.1)
				(type default)
			)
			(layer "F.Fab")
		)
		(fp_line
			(start -2.3749 -1.970024)
			(end -2.3749 1.970024)
			(stroke
				(width 0.1)
				(type default)
			)
			(layer "F.Fab")
		)
		(fp_line
			(start 2.3749 -1.970024)
			(end -2.3749 -1.970024)
			(stroke
				(width 0.1)
				(type default)
			)
			(layer "F.Fab")
		)
		(fp_text user "+"
			(at -4.9784 -0.23495 270)
			(unlocked yes)
			(layer "F.Fab")
			(effects
				(font
					(size 1.905 1.4224)
					(thickness 0.1524)
				)
				(justify left)
			)
		)
		(fp_text user "-"
			(at 4.1656 -0.23495 270)
			(unlocked yes)
			(layer "F.Fab")
			(effects
				(font
					(size 1.905 1.4224)
					(thickness 0.1524)
				)
				(justify left)
			)
		)
		(pad "A" smd rect
			(at -2.450084 0 270)
			(size 2.159 2.2606)
			(layers "F.Cu" "F.Mask" "F.Paste")
			(net "GND")
		)
		(pad "C" smd rect
			(at 2.450084 0 270)
			(size 2.159 2.2606)
			(layers "F.Cu" "F.Mask" "F.Paste")
			(net "P12V_AUX")
		)
	)
	(footprint ""
		(layer "F.Cu")
		(at 323.579236 -300.641004 -90)
		(property "Reference" "R3972"
			(at 0 0 270)
			(layer "F.SilkS")
			(hide yes)
			(effects
				(font
					(size 1.27 1.27)
				)
			)
		)
		(property "Value" ""
			(at 0 0 270)
			(layer "F.Fab")
			(effects
				(font
					(size 1.27 1.27)
				)
			)
		)
		(duplicate_pad_numbers_are_jumpers no)
		(fp_line
			(start -0.7874 0.4064)
			(end -0.7874 -0.4064)
			(stroke
				(width 0.1524)
				(type default)
			)
			(layer "F.SilkS")
		)
		(fp_line
			(start 0.7874 0.4064)
			(end -0.7874 0.4064)
			(stroke
				(width 0.1524)
				(type default)
			)
			(layer "F.SilkS")
		)
		(fp_line
			(start -0.7874 -0.4064)
			(end 0.7874 -0.4064)
			(stroke
				(width 0.1524)
				(type default)
			)
			(layer "F.SilkS")
		)
		(fp_line
			(start 0.7874 -0.4064)
			(end 0.7874 0.4064)
			(stroke
				(width 0.1524)
				(type default)
			)
			(layer "F.SilkS")
		)
		(fp_line
			(start -0.67945 0.3048)
			(end -0.67945 -0.305054)
			(stroke
				(width 0.1)
				(type default)
			)
			(layer "F.Fab")
		)
		(fp_line
			(start -0.12065 0.3048)
			(end -0.67945 0.3048)
			(stroke
				(width 0.1)
				(type default)
			)
			(layer "F.Fab")
		)
		(fp_line
			(start 0.120396 0.3048)
			(end 0.120396 0.2794)
			(stroke
				(width 0.1)
				(type default)
			)
			(layer "F.Fab")
		)
		(fp_line
			(start 0.67945 0.3048)
			(end 0.120396 0.3048)
			(stroke
				(width 0.1)
				(type default)
			)
			(layer "F.Fab")
		)
		(fp_line
			(start -0.12065 0.2794)
			(end -0.12065 0.3048)
			(stroke
				(width 0.1)
				(type default)
			)
			(layer "F.Fab")
		)
		(fp_line
			(start 0.120396 0.2794)
			(end -0.12065 0.2794)
			(stroke
				(width 0.1)
				(type default)
			)
			(layer "F.Fab")
		)
		(fp_line
			(start -0.12065 -0.2794)
			(end 0.12065 -0.2794)
			(stroke
				(width 0.1)
				(type default)
			)
			(layer "F.Fab")
		)
		(fp_line
			(start 0.12065 -0.2794)
			(end 0.12065 -0.3048)
			(stroke
				(width 0.1)
				(type default)
			)
			(layer "F.Fab")
		)
		(fp_line
			(start 0.12065 -0.3048)
			(end 0.67945 -0.3048)
			(stroke
				(width 0.1)
				(type default)
			)
			(layer "F.Fab")
		)
		(fp_line
			(start 0.67945 -0.3048)
			(end 0.67945 0.3048)
			(stroke
				(width 0.1)
				(type default)
			)
			(layer "F.Fab")
		)
		(fp_line
			(start -0.67945 -0.305054)
			(end -0.12065 -0.305054)
			(stroke
				(width 0.1)
				(type default)
			)
			(layer "F.Fab")
		)
		(fp_line
			(start -0.12065 -0.305054)
			(end -0.12065 -0.2794)
			(stroke
				(width 0.1)
				(type default)
			)
			(layer "F.Fab")
		)
		(pad "1" smd circle
			(at -0.40005 0 270)
			(size 0 0)
			(layers "F.Cu" "F.Mask" "F.Paste")
			(net "I2C0_PEX2_SCL")
		)
		(pad "2" smd circle
			(at 0.40005 0 270)
			(size 0 0)
			(layers "F.Cu" "F.Mask" "F.Paste")
			(net "I2C_PEX2_HOST_SCL")
		)
	)
)
